(kicad_pcb
	(version 20260206)
	(generator "pcbnew")
	(generator_version "10.0")
	(general
		(thickness 1.6)
		(legacy_teardrops no)
	)
	(paper "A4")
	(title_block
		(title "Wiwynn_Tioga_Pass_MB.brd")
		(comment 1 "Tioga Pass / footprints 3167-3174 of 4770")
	)
	(layers
		(0 "F.Cu" signal "TOP")
		(4 "In1.Cu" signal "L2GND")
		(6 "In2.Cu" signal "L3")
		(8 "In3.Cu" signal "L4GND")
		(10 "In4.Cu" signal "L5")
		(12 "In5.Cu" signal "L6GND")
		(14 "In6.Cu" signal "L7VCC")
		(16 "In7.Cu" signal "L8VCC")
		(18 "In8.Cu" signal "L9GND")
		(20 "In9.Cu" signal "L10")
		(22 "In10.Cu" signal "L11GND")
		(24 "In11.Cu" signal "L12")
		(26 "In12.Cu" signal "L13GND")
		(2 "B.Cu" signal "BOTTOM")
		(9 "F.Adhes" user "F.Adhesive")
		(11 "B.Adhes" user "B.Adhesive")
		(13 "F.Paste" user "Package Geometry/Pastemask Top")
		(15 "B.Paste" user "Package Geometry/Pastemask Bottom")
		(5 "F.SilkS" user "Ref Des/Silkscreen Top")
		(7 "B.SilkS" user "Ref Des/Silkscreen Bottom")
		(1 "F.Mask" user "Board Geometry/Soldermask Top")
		(3 "B.Mask" user "Board Geometry/Soldermask Bottom")
		(17 "Dwgs.User" user "User.Drawings")
		(19 "Cmts.User" user "User.Comments")
		(21 "Eco1.User" user "User.Eco1")
		(23 "Eco2.User" user "User.Eco2")
		(25 "Edge.Cuts" user "Board Geometry/Outline")
		(27 "Margin" user)
		(31 "F.CrtYd" user "Package Geometry/Place Bound Top")
		(29 "B.CrtYd" user "Package Geometry/Place Bound Bottom")
		(35 "F.Fab" user "Ref Des/Assembly Top")
		(33 "B.Fab" user "Ref Des/Assembly Bottom")
	)
	(footprint ""
		(layer "B.Cu")
		(at 183.515 -145.796 180)
		(property "Reference" "R6L10"
			(at 0 0 0)
			(layer "B.SilkS")
			(hide yes)
			(effects
				(font
					(size 1.27 1.27)
				)
				(justify mirror)
			)
		)
		(property "Value" ""
			(at 0 0 0)
			(layer "B.Fab")
			(effects
				(font
					(size 1.27 1.27)
				)
				(justify mirror)
			)
		)
		(duplicate_pad_numbers_are_jumpers no)
		(fp_rect
			(start 0.2794 0.9906)
			(end -0.2794 -0.1016)
			(stroke
				(width 0)
				(type default)
			)
			(fill no)
			(layer "B.CrtYd")
		)
		(fp_line
			(start 0.2794 0.9906)
			(end -0.2794 0.9906)
			(stroke
				(width 0.1)
				(type default)
			)
			(layer "B.Fab")
		)
		(fp_line
			(start 0.2794 -0.1016)
			(end 0.2794 0.9906)
			(stroke
				(width 0.1)
				(type default)
			)
			(layer "B.Fab")
		)
		(fp_line
			(start -0.2794 0.9906)
			(end -0.2794 -0.1016)
			(stroke
				(width 0.1)
				(type default)
			)
			(layer "B.Fab")
		)
		(fp_line
			(start -0.2794 -0.1016)
			(end 0.2794 -0.1016)
			(stroke
				(width 0.1)
				(type default)
			)
			(layer "B.Fab")
		)
		(pad "1" smd rect
			(at 0 0)
			(size 0.508 0.508)
			(layers "B.Cu" "B.Mask" "B.Paste")
			(net "PVDDQ_DEF")
		)
		(pad "2" smd rect
			(at 0 0.889)
			(size 0.508 0.508)
			(layers "B.Cu" "B.Mask" "B.Paste")
			(net "VSENSE_PVDDQ_DEF_VTT")
		)
		(zone
			(layer "B.Cu")
			(hatch none 0.5)
			(connect_pads
				(clearance 0)
			)
			(min_thickness 0.25)
			(keepout
				(tracks not_allowed)
				(vias allowed)
				(pads allowed)
				(copperpour not_allowed)
				(footprints allowed)
			)
			(placement
				(enabled no)
				(sheetname "")
			)
			(fill
				(thermal_gap 0.5)
				(thermal_bridge_width 0.5)
				(island_removal_mode 0)
			)
			(polygon
				(pts
					(xy 183.261 -146.431) (xy 183.261 -146.05) (xy 183.769 -146.05) (xy 183.769 -146.431)
				)
			)
		)
		(zone
			(layer "B.Cu")
			(hatch none 0.5)
			(connect_pads
				(clearance 0)
			)
			(min_thickness 0.25)
			(keepout
				(tracks allowed)
				(vias not_allowed)
				(pads allowed)
				(copperpour not_allowed)
				(footprints allowed)
			)
			(placement
				(enabled no)
				(sheetname "")
			)
			(fill
				(thermal_gap 0.5)
				(thermal_bridge_width 0.5)
				(island_removal_mode 0)
			)
			(polygon
				(pts
					(xy 183.261 -146.431) (xy 183.261 -146.05) (xy 183.769 -146.05) (xy 183.769 -146.431)
				)
			)
		)
	)
	(footprint ""
		(layer "B.Cu")
		(at 115.734592 -80.096614 180)
		(property "Reference" "C7P3"
			(at 0 0 0)
			(layer "B.SilkS")
			(hide yes)
			(effects
				(font
					(size 1.27 1.27)
				)
				(justify mirror)
			)
		)
		(property "Value" ""
			(at 0 0 0)
			(layer "B.Fab")
			(effects
				(font
					(size 1.27 1.27)
				)
				(justify mirror)
			)
		)
		(duplicate_pad_numbers_are_jumpers no)
		(fp_poly
			(pts
				(xy 0.7239 -0.2159) (xy -0.7239 -0.2159) (xy -0.7239 1.9939) (xy 0.7239 1.9939)
			)
			(stroke
				(width 0)
				(type default)
			)
			(fill no)
			(layer "B.CrtYd")
		)
		(fp_line
			(start 0.7239 1.9939)
			(end -0.7239 1.9939)
			(stroke
				(width 0.1)
				(type default)
			)
			(layer "B.Fab")
		)
		(fp_line
			(start 0.7239 -0.2159)
			(end 0.7239 1.9939)
			(stroke
				(width 0.1)
				(type default)
			)
			(layer "B.Fab")
		)
		(fp_line
			(start -0.7239 1.9939)
			(end -0.7239 -0.2159)
			(stroke
				(width 0.1)
				(type default)
			)
			(layer "B.Fab")
		)
		(fp_line
			(start -0.7239 -0.2159)
			(end 0.7239 -0.2159)
			(stroke
				(width 0.1)
				(type default)
			)
			(layer "B.Fab")
		)
		(pad "1" smd rect
			(at 0 0)
			(size 1.27 1.016)
			(layers "B.Cu" "B.Mask" "B.Paste")
			(net "PVCCIO_CPU1")
		)
		(pad "2" smd rect
			(at 0 1.778)
			(size 1.27 1.016)
			(layers "B.Cu" "B.Mask" "B.Paste")
			(net "GND")
		)
		(zone
			(layer "B.Cu")
			(hatch none 0.5)
			(connect_pads
				(clearance 0)
			)
			(min_thickness 0.25)
			(keepout
				(tracks not_allowed)
				(vias allowed)
				(pads allowed)
				(copperpour not_allowed)
				(footprints allowed)
			)
			(placement
				(enabled no)
				(sheetname "")
			)
			(fill
				(thermal_gap 0.5)
				(thermal_bridge_width 0.5)
				(island_removal_mode 0)
			)
			(polygon
				(pts
					(xy 115.099592 -80.604614) (xy 116.369592 -80.604614) (xy 116.369592 -81.366614) (xy 115.099592 -81.366614)
				)
			)
		)
	)
	(footprint ""
		(layer "B.Cu")
		(at 195.3006 -88.4428 90)
		(property "Reference" "CT34"
			(at 0.8382 -0.84963 90)
			(unlocked yes)
			(layer "B.SilkS")
			(effects
				(font
					(size 0.7874 0.5842)
					(thickness 0.1524)
				)
				(justify left mirror)
			)
		)
		(property "Value" ""
			(at 0 0 90)
			(layer "B.Fab")
			(effects
				(font
					(size 1.27 1.27)
				)
				(justify mirror)
			)
		)
		(duplicate_pad_numbers_are_jumpers no)
		(fp_poly
			(pts
				(xy -0.3048 -0.1016) (xy -0.3048 0.9906) (xy 0.3048 0.9906) (xy 0.3048 -0.1016)
			)
			(stroke
				(width 0)
				(type default)
			)
			(fill no)
			(layer "B.CrtYd")
		)
		(fp_line
			(start 0.3048 -0.1016)
			(end 0.3048 0.9906)
			(stroke
				(width 0.1)
				(type default)
			)
			(layer "B.Fab")
		)
		(fp_line
			(start -0.3048 -0.1016)
			(end 0.3048 -0.1016)
			(stroke
				(width 0.1)
				(type default)
			)
			(layer "B.Fab")
		)
		(fp_line
			(start 0.3048 0.9906)
			(end -0.3048 0.9906)
			(stroke
				(width 0.1)
				(type default)
			)
			(layer "B.Fab")
		)
		(fp_line
			(start -0.3048 0.9906)
			(end -0.3048 -0.1016)
			(stroke
				(width 0.1)
				(type default)
			)
			(layer "B.Fab")
		)
		(pad "1" smd rect
			(at 0 0 270)
			(size 0.508 0.508)
			(layers "B.Cu" "B.Mask" "B.Paste")
			(net "A_TSENSE_PVCCIN_CPU0")
		)
		(pad "2" smd rect
			(at 0 0.889 270)
			(size 0.508 0.508)
			(layers "B.Cu" "B.Mask" "B.Paste")
			(net "GND")
		)
		(zone
			(layer "B.Cu")
			(hatch none 0.5)
			(connect_pads
				(clearance 0)
			)
			(min_thickness 0.25)
			(keepout
				(tracks allowed)
				(vias not_allowed)
				(pads allowed)
				(copperpour not_allowed)
				(footprints allowed)
			)
			(placement
				(enabled no)
				(sheetname "")
			)
			(fill
				(thermal_gap 0.5)
				(thermal_bridge_width 0.5)
				(island_removal_mode 0)
			)
			(polygon
				(pts
					(xy 195.5546 -88.6968) (xy 195.5546 -88.1888) (xy 195.9356 -88.1888) (xy 195.9356 -88.6968)
				)
			)
		)
		(zone
			(layer "B.Cu")
			(hatch none 0.5)
			(connect_pads
				(clearance 0)
			)
			(min_thickness 0.25)
			(keepout
				(tracks not_allowed)
				(vias allowed)
				(pads allowed)
				(copperpour not_allowed)
				(footprints allowed)
			)
			(placement
				(enabled no)
				(sheetname "")
			)
			(fill
				(thermal_gap 0.5)
				(thermal_bridge_width 0.5)
				(island_removal_mode 0)
			)
			(polygon
				(pts
					(xy 195.9356 -88.6968) (xy 195.9356 -88.1888) (xy 195.5546 -88.1888) (xy 195.5546 -88.6968)
				)
			)
		)
	)
	(footprint ""
		(layer "B.Cu")
		(at 399.923 -57.658)
		(property "Reference" "R3T1"
			(at 0 0 0)
			(layer "B.SilkS")
			(hide yes)
			(effects
				(font
					(size 1.27 1.27)
				)
				(justify mirror)
			)
		)
		(property "Value" ""
			(at 0 0 0)
			(layer "B.Fab")
			(effects
				(font
					(size 1.27 1.27)
				)
				(justify mirror)
			)
		)
		(duplicate_pad_numbers_are_jumpers no)
		(fp_poly
			(pts
				(xy 0.2794 -0.1016) (xy -0.2794 -0.1016) (xy -0.2794 0.9906) (xy 0.2794 0.9906)
			)
			(stroke
				(width 0)
				(type default)
			)
			(fill no)
			(layer "B.CrtYd")
		)
		(fp_line
			(start -0.2794 -0.1016)
			(end 0.2794 -0.1016)
			(stroke
				(width 0.1)
				(type default)
			)
			(layer "B.Fab")
		)
		(fp_line
			(start -0.2794 0.9906)
			(end -0.2794 -0.1016)
			(stroke
				(width 0.1)
				(type default)
			)
			(layer "B.Fab")
		)
		(fp_line
			(start 0.2794 -0.1016)
			(end 0.2794 0.9906)
			(stroke
				(width 0.1)
				(type default)
			)
			(layer "B.Fab")
		)
		(fp_line
			(start 0.2794 0.9906)
			(end -0.2794 0.9906)
			(stroke
				(width 0.1)
				(type default)
			)
			(layer "B.Fab")
		)
		(pad "1" smd rect
			(at 0 0 180)
			(size 0.508 0.508)
			(layers "B.Cu" "B.Mask" "B.Paste")
			(net "SPI_BIOS_SOCKET_IO3")
		)
		(pad "2" smd rect
			(at 0 0.889 180)
			(size 0.508 0.508)
			(layers "B.Cu" "B.Mask" "B.Paste")
			(net "PU_BIOS_SPI_HOLD1_N")
		)
		(zone
			(layer "B.Cu")
			(hatch none 0.5)
			(connect_pads
				(clearance 0)
			)
			(min_thickness 0.25)
			(keepout
				(tracks allowed)
				(vias not_allowed)
				(pads allowed)
				(copperpour not_allowed)
				(footprints allowed)
			)
			(placement
				(enabled no)
				(sheetname "")
			)
			(fill
				(thermal_gap 0.5)
				(thermal_bridge_width 0.5)
				(island_removal_mode 0)
			)
			(polygon
				(pts
					(xy 400.177 -57.404) (xy 399.669 -57.404) (xy 399.669 -57.023) (xy 400.177 -57.023)
				)
			)
		)
		(zone
			(layer "B.Cu")
			(hatch none 0.5)
			(connect_pads
				(clearance 0)
			)
			(min_thickness 0.25)
			(keepout
				(tracks not_allowed)
				(vias allowed)
				(pads allowed)
				(copperpour not_allowed)
				(footprints allowed)
			)
			(placement
				(enabled no)
				(sheetname "")
			)
			(fill
				(thermal_gap 0.5)
				(thermal_bridge_width 0.5)
				(island_removal_mode 0)
			)
			(polygon
				(pts
					(xy 400.177 -57.023) (xy 399.669 -57.023) (xy 399.669 -57.404) (xy 400.177 -57.404)
				)
			)
		)
	)
	(footprint ""
		(layer "B.Cu")
		(at 479.9076 -41.529 90)
		(property "Reference" "C1R30"
			(at 0 0 90)
			(layer "B.SilkS")
			(hide yes)
			(effects
				(font
					(size 1.27 1.27)
				)
				(justify mirror)
			)
		)
		(property "Value" ""
			(at 0 0 90)
			(layer "B.Fab")
			(effects
				(font
					(size 1.27 1.27)
				)
				(justify mirror)
			)
		)
		(duplicate_pad_numbers_are_jumpers no)
		(fp_poly
			(pts
				(xy 0.4953 -0.2032) (xy -0.4953 -0.2032) (xy -0.4953 1.6002) (xy 0.4953 1.6002)
			)
			(stroke
				(width 0)
				(type default)
			)
			(fill no)
			(layer "B.CrtYd")
		)
		(fp_line
			(start 0.4953 -0.2032)
			(end -0.4953 -0.2032)
			(stroke
				(width 0.1)
				(type default)
			)
			(layer "B.Fab")
		)
		(fp_line
			(start -0.4953 -0.2032)
			(end -0.4953 1.6002)
			(stroke
				(width 0.1)
				(type default)
			)
			(layer "B.Fab")
		)
		(fp_line
			(start 0.4953 1.6002)
			(end 0.4953 -0.2032)
			(stroke
				(width 0.1)
				(type default)
			)
			(layer "B.Fab")
		)
		(fp_line
			(start -0.4953 1.6002)
			(end 0.4953 1.6002)
			(stroke
				(width 0.1)
				(type default)
			)
			(layer "B.Fab")
		)
		(pad "1" smd rect
			(at 0 0 270)
			(size 0.762 0.889)
			(layers "B.Cu" "B.Mask" "B.Paste")
			(net "P1V5_LAN")
		)
		(pad "2" smd rect
			(at 0 1.397 270)
			(size 0.762 0.889)
			(layers "B.Cu" "B.Mask" "B.Paste")
			(net "GND")
		)
		(zone
			(layer "B.Cu")
			(hatch none 0.5)
			(connect_pads
				(clearance 0)
			)
			(min_thickness 0.25)
			(keepout
				(tracks not_allowed)
				(vias allowed)
				(pads allowed)
				(copperpour not_allowed)
				(footprints allowed)
			)
			(placement
				(enabled no)
				(sheetname "")
			)
			(fill
				(thermal_gap 0.5)
				(thermal_bridge_width 0.5)
				(island_removal_mode 0)
			)
			(polygon
				(pts
					(xy 480.3521 -41.91) (xy 480.3521 -41.148) (xy 480.8601 -41.148) (xy 480.8601 -41.91)
				)
			)
		)
	)
	(footprint ""
		(layer "B.Cu")
		(at 437.642 -141.986)
		(property "Reference" "R25W186"
			(at 0.8382 -0.67818 0)
			(unlocked yes)
			(layer "B.SilkS")
			(effects
				(font
					(size 0.4064 0.254)
					(thickness 0.1524)
				)
				(justify left mirror)
			)
		)
		(property "Value" ""
			(at 0 0 0)
			(layer "B.Fab")
			(effects
				(font
					(size 1.27 1.27)
				)
				(justify mirror)
			)
		)
		(duplicate_pad_numbers_are_jumpers no)
		(fp_poly
			(pts
				(xy 0.2794 -0.1016) (xy -0.2794 -0.1016) (xy -0.2794 0.9906) (xy 0.2794 0.9906)
			)
			(stroke
				(width 0)
				(type default)
			)
			(fill no)
			(layer "B.CrtYd")
		)
		(fp_line
			(start -0.2794 -0.1016)
			(end 0.2794 -0.1016)
			(stroke
				(width 0.1)
				(type default)
			)
			(layer "B.Fab")
		)
		(fp_line
			(start -0.2794 0.9906)
			(end -0.2794 -0.1016)
			(stroke
				(width 0.1)
				(type default)
			)
			(layer "B.Fab")
		)
		(fp_line
			(start 0.2794 -0.1016)
			(end 0.2794 0.9906)
			(stroke
				(width 0.1)
				(type default)
			)
			(layer "B.Fab")
		)
		(fp_line
			(start 0.2794 0.9906)
			(end -0.2794 0.9906)
			(stroke
				(width 0.1)
				(type default)
			)
			(layer "B.Fab")
		)
		(pad "1" smd rect
			(at 0 0 180)
			(size 0.508 0.508)
			(layers "B.Cu" "B.Mask" "B.Paste")
			(net "BMC_JTAG_SEL_N")
		)
		(pad "2" smd rect
			(at 0 0.889 180)
			(size 0.508 0.508)
			(layers "B.Cu" "B.Mask" "B.Paste")
			(net "FM_JTAG_PLD_EN_DEBUG")
		)
		(zone
			(layer "B.Cu")
			(hatch none 0.5)
			(connect_pads
				(clearance 0)
			)
			(min_thickness 0.25)
			(keepout
				(tracks allowed)
				(vias not_allowed)
				(pads allowed)
				(copperpour not_allowed)
				(footprints allowed)
			)
			(placement
				(enabled no)
				(sheetname "")
			)
			(fill
				(thermal_gap 0.5)
				(thermal_bridge_width 0.5)
				(island_removal_mode 0)
			)
			(polygon
				(pts
					(xy 437.896 -141.732) (xy 437.388 -141.732) (xy 437.388 -141.351) (xy 437.896 -141.351)
				)
			)
		)
		(zone
			(layer "B.Cu")
			(hatch none 0.5)
			(connect_pads
				(clearance 0)
			)
			(min_thickness 0.25)
			(keepout
				(tracks not_allowed)
				(vias allowed)
				(pads allowed)
				(copperpour not_allowed)
				(footprints allowed)
			)
			(placement
				(enabled no)
				(sheetname "")
			)
			(fill
				(thermal_gap 0.5)
				(thermal_bridge_width 0.5)
				(island_removal_mode 0)
			)
			(polygon
				(pts
					(xy 437.896 -141.351) (xy 437.388 -141.351) (xy 437.388 -141.732) (xy 437.896 -141.732)
				)
			)
		)
	)
	(footprint ""
		(layer "B.Cu")
		(at 448.6656 -151.384 180)
		(property "Reference" "Q25W5"
			(at 0.229362 -1.59512 180)
			(unlocked yes)
			(layer "B.SilkS")
			(effects
				(font
					(size 1.27 0.9652)
					(thickness 0.1524)
				)
				(justify left mirror)
			)
		)
		(property "Value" ""
			(at 0 0 0)
			(layer "B.Fab")
			(effects
				(font
					(size 1.27 1.27)
				)
				(justify mirror)
			)
		)
		(duplicate_pad_numbers_are_jumpers no)
		(fp_line
			(start -0.381 0.635)
			(end -0.381 1.27)
			(stroke
				(width 0.1524)
				(type default)
			)
			(layer "B.SilkS")
		)
		(fp_line
			(start -0.9525 2.4765)
			(end -1.778 2.4765)
			(stroke
				(width 0.1524)
				(type default)
			)
			(layer "B.SilkS")
		)
		(fp_line
			(start -0.9525 -0.5715)
			(end -1.778 -0.5715)
			(stroke
				(width 0.1524)
				(type default)
			)
			(layer "B.SilkS")
		)
		(fp_line
			(start -1.778 2.4765)
			(end -1.778 1.5875)
			(stroke
				(width 0.1524)
				(type default)
			)
			(layer "B.SilkS")
		)
		(fp_line
			(start -1.778 -0.5715)
			(end -1.778 0.3175)
			(stroke
				(width 0.1524)
				(type default)
			)
			(layer "B.SilkS")
		)
		(fp_circle
			(center 0.9525 -0.9271)
			(end 0.8255 -0.9271)
			(stroke
				(width 0.254)
				(type default)
			)
			(fill no)
			(layer "B.SilkS")
		)
		(fp_poly
			(pts
				(xy -1.778 2.4765) (xy -0.381 2.4765) (xy -0.381 -0.5715) (xy -1.778 -0.5715)
			)
			(stroke
				(width 0)
				(type default)
			)
			(fill no)
			(layer "B.CrtYd")
		)
		(fp_line
			(start -0.381 2.4765)
			(end -1.778 2.4765)
			(stroke
				(width 0.1)
				(type default)
			)
			(layer "B.Fab")
		)
		(fp_line
			(start -0.381 -0.5715)
			(end -0.381 2.4765)
			(stroke
				(width 0.1)
				(type default)
			)
			(layer "B.Fab")
		)
		(fp_line
			(start -1.778 2.4765)
			(end -1.778 -0.5715)
			(stroke
				(width 0.1)
				(type default)
			)
			(layer "B.Fab")
		)
		(fp_line
			(start -1.778 -0.5715)
			(end -0.381 -0.5715)
			(stroke
				(width 0.1)
				(type default)
			)
			(layer "B.Fab")
		)
		(fp_circle
			(center 0.9525 -0.9271)
			(end 0.8255 -0.9271)
			(stroke
				(width 0.254)
				(type default)
			)
			(fill no)
			(layer "B.Fab")
		)
		(pad "1" smd rect
			(at 0 0)
			(size 1.143 0.508)
			(layers "B.Cu" "B.Mask" "B.Paste")
			(net "BMC_JTAG_SEL_N")
		)
		(pad "2" smd rect
			(at 0 1.905)
			(size 1.143 0.508)
			(layers "B.Cu" "B.Mask" "B.Paste")
			(net "GND")
		)
		(pad "3" smd rect
			(at -2.159 0.9525)
			(size 1.143 0.508)
			(layers "B.Cu" "B.Mask" "B.Paste")
			(net "BMC_JTAG_SEL")
		)
	)
	(footprint ""
		(layer "B.Cu")
		(at 407.416 -31.6865 -90)
		(property "Reference" "C1W21"
			(at -0.97536 0.76708 0)
			(unlocked yes)
			(layer "B.SilkS")
			(effects
				(font
					(size 0.4064 0.254)
					(thickness 0.1524)
				)
				(justify mirror)
			)
		)
		(property "Value" ""
			(at 0 0 90)
			(layer "B.Fab")
			(effects
				(font
					(size 1.27 1.27)
				)
				(justify mirror)
			)
		)
		(duplicate_pad_numbers_are_jumpers no)
		(fp_poly
			(pts
				(xy 0.4953 -0.2032) (xy -0.4953 -0.2032) (xy -0.4953 1.6002) (xy 0.4953 1.6002)
			)
			(stroke
				(width 0)
				(type default)
			)
			(fill no)
			(layer "B.CrtYd")
		)
		(fp_line
			(start -0.4953 1.6002)
			(end 0.4953 1.6002)
			(stroke
				(width 0.1)
				(type default)
			)
			(layer "B.Fab")
		)
		(fp_line
			(start 0.4953 1.6002)
			(end 0.4953 -0.2032)
			(stroke
				(width 0.1)
				(type default)
			)
			(layer "B.Fab")
		)
		(fp_line
			(start -0.4953 -0.2032)
			(end -0.4953 1.6002)
			(stroke
				(width 0.1)
				(type default)
			)
			(layer "B.Fab")
		)
		(fp_line
			(start 0.4953 -0.2032)
			(end -0.4953 -0.2032)
			(stroke
				(width 0.1)
				(type default)
			)
			(layer "B.Fab")
		)
		(pad "1" smd rect
			(at 0 0 90)
			(size 0.762 0.889)
			(layers "B.Cu" "B.Mask" "B.Paste")
			(net "A_USB2AVRES")
		)
		(pad "2" smd rect
			(at 0 1.397 90)
			(size 0.762 0.889)
			(layers "B.Cu" "B.Mask" "B.Paste")
			(net "GND")
		)
		(zone
			(layer "B.Cu")
			(hatch none 0.5)
			(connect_pads
				(clearance 0)
			)
			(min_thickness 0.25)
			(keepout
				(tracks not_allowed)
				(vias allowed)
				(pads allowed)
				(copperpour not_allowed)
				(footprints allowed)
			)
			(placement
				(enabled no)
				(sheetname "")
			)
			(fill
				(thermal_gap 0.5)
				(thermal_bridge_width 0.5)
				(island_removal_mode 0)
			)
			(polygon
				(pts
					(xy 406.9715 -31.3055) (xy 406.9715 -32.0675) (xy 406.4635 -32.0675) (xy 406.4635 -31.3055)
				)
			)
		)
	)
)
